# T6G (Grand Teton) — schematic netlist excerpt (pin names and nets, part order shuffled) for the footprints in the layout excerpt that follows; sources: Cadence DE-HDL packaged netlist, KiCad conversion of 04192023_DAF0TMB3IC0_F0TG_MB_C_brd_V02_OCP.brd

C6511  Q_CAP_DIFFBUS  DIFF BUS_0.22UF 6.3V 20% X6S  pkg C0201  page 275 : \1\ = P5E_CPU0_P0_TX_BUF_C_DP<5> ; \2\ = P5E_CPU0_P0_TX_BUF_DP<5>
C1058  Q_CAP  0.1UF 25V 10% X7R  pkg 0402  page 136 : A = P3V3_AUX ; B = GND
R3437  Q_RES  100K 1% CHIP  pkg 0402LF  page 126 : A = P3V3_AUX ; B = GPU_FPGA_OVERT_ISO_N

(kicad_pcb
	(version 20260206)
	(generator "pcbnew")
	(generator_version "10.0")
	(general
		(thickness 1.6)
		(legacy_teardrops no)
	)
	(paper "A4")
	(title_block
		(title "04192023_DAF0TMB3IC0_F0TG_MB_C_brd_V02_OCP.brd")
		(comment 1 "Grand Teton / footprints 548-550 of 8354")
	)
	(layers
		(0 "F.Cu" signal "TOP")
		(4 "In1.Cu" signal "GND")
		(6 "In2.Cu" signal "IN1")
		(8 "In3.Cu" signal "GND1")
		(10 "In4.Cu" signal "IN2")
		(12 "In5.Cu" signal "GND2")
		(14 "In6.Cu" signal "IN3")
		(16 "In7.Cu" signal "GND3")
		(18 "In8.Cu" signal "VCC")
		(20 "In9.Cu" signal "VCC1")
		(22 "In10.Cu" signal "GND4")
		(24 "In11.Cu" signal "IN4")
		(26 "In12.Cu" signal "GND5")
		(28 "In13.Cu" signal "IN5")
		(30 "In14.Cu" signal "GND6")
		(32 "In15.Cu" signal "IN6")
		(34 "In16.Cu" signal "GND7")
		(2 "B.Cu" signal "BOTTOM")
		(9 "F.Adhes" user "F.Adhesive")
		(11 "B.Adhes" user "B.Adhesive")
		(13 "F.Paste" user "Package Geometry/Pastemask Top")
		(15 "B.Paste" user "Package Geometry/Pastemask Bottom")
		(5 "F.SilkS" user "Ref Des/Silkscreen Top")
		(7 "B.SilkS" user "Ref Des/Silkscreen Bottom")
		(1 "F.Mask" user "Board Geometry/Soldermask Top")
		(3 "B.Mask" user "Board Geometry/Soldermask Bottom")
		(17 "Dwgs.User" user "User.Drawings")
		(19 "Cmts.User" user "User.Comments")
		(21 "Eco1.User" user "User.Eco1")
		(23 "Eco2.User" user "User.Eco2")
		(25 "Edge.Cuts" user "Board Geometry/Outline")
		(27 "Margin" user)
		(31 "F.CrtYd" user "Package Geometry/Place Bound Top")
		(29 "B.CrtYd" user "Package Geometry/Place Bound Bottom")
		(35 "F.Fab" user "Ref Des/Assembly Top")
		(33 "B.Fab" user "Ref Des/Assembly Bottom")
	)
	(footprint ""
		(layer "F.Cu")
		(at 308.420516 -435.720744 -90)
		(property "Reference" "R3437"
			(at 0 0 270)
			(layer "F.SilkS")
			(hide yes)
			(effects
				(font
					(size 1.27 1.27)
				)
			)
		)
		(property "Value" ""
			(at 0 0 270)
			(layer "F.Fab")
			(effects
				(font
					(size 1.27 1.27)
				)
			)
		)
		(duplicate_pad_numbers_are_jumpers no)
		(fp_line
			(start -0.7874 0.4064)
			(end -0.7874 -0.4064)
			(stroke
				(width 0.1524)
				(type default)
			)
			(layer "F.SilkS")
		)
		(fp_line
			(start 0.7874 0.4064)
			(end -0.7874 0.4064)
			(stroke
				(width 0.1524)
				(type default)
			)
			(layer "F.SilkS")
		)
		(fp_line
			(start -0.7874 -0.4064)
			(end 0.7874 -0.4064)
			(stroke
				(width 0.1524)
				(type default)
			)
			(layer "F.SilkS")
		)
		(fp_line
			(start 0.7874 -0.4064)
			(end 0.7874 0.4064)
			(stroke
				(width 0.1524)
				(type default)
			)
			(layer "F.SilkS")
		)
		(fp_line
			(start -0.67945 0.3048)
			(end -0.67945 -0.305054)
			(stroke
				(width 0.1)
				(type default)
			)
			(layer "F.Fab")
		)
		(fp_line
			(start -0.12065 0.3048)
			(end -0.67945 0.3048)
			(stroke
				(width 0.1)
				(type default)
			)
			(layer "F.Fab")
		)
		(fp_line
			(start 0.120396 0.3048)
			(end 0.120396 0.2794)
			(stroke
				(width 0.1)
				(type default)
			)
			(layer "F.Fab")
		)
		(fp_line
			(start 0.67945 0.3048)
			(end 0.120396 0.3048)
			(stroke
				(width 0.1)
				(type default)
			)
			(layer "F.Fab")
		)
		(fp_line
			(start -0.12065 0.2794)
			(end -0.12065 0.3048)
			(stroke
				(width 0.1)
				(type default)
			)
			(layer "F.Fab")
		)
		(fp_line
			(start 0.120396 0.2794)
			(end -0.12065 0.2794)
			(stroke
				(width 0.1)
				(type default)
			)
			(layer "F.Fab")
		)
		(fp_line
			(start -0.12065 -0.2794)
			(end 0.12065 -0.2794)
			(stroke
				(width 0.1)
				(type default)
			)
			(layer "F.Fab")
		)
		(fp_line
			(start 0.12065 -0.2794)
			(end 0.12065 -0.3048)
			(stroke
				(width 0.1)
				(type default)
			)
			(layer "F.Fab")
		)
		(fp_line
			(start 0.12065 -0.3048)
			(end 0.67945 -0.3048)
			(stroke
				(width 0.1)
				(type default)
			)
			(layer "F.Fab")
		)
		(fp_line
			(start 0.67945 -0.3048)
			(end 0.67945 0.3048)
			(stroke
				(width 0.1)
				(type default)
			)
			(layer "F.Fab")
		)
		(fp_line
			(start -0.67945 -0.305054)
			(end -0.12065 -0.305054)
			(stroke
				(width 0.1)
				(type default)
			)
			(layer "F.Fab")
		)
		(fp_line
			(start -0.12065 -0.305054)
			(end -0.12065 -0.2794)
			(stroke
				(width 0.1)
				(type default)
			)
			(layer "F.Fab")
		)
		(pad "1" smd circle
			(at -0.40005 0 270)
			(size 0 0)
			(layers "F.Cu" "F.Mask" "F.Paste")
			(net "P3V3_AUX")
		)
		(pad "2" smd circle
			(at 0.40005 0 270)
			(size 0 0)
			(layers "F.Cu" "F.Mask" "F.Paste")
			(net "GPU_FPGA_OVERT_ISO_N")
		)
	)
	(footprint ""
		(layer "F.Cu")
		(at 319.999106 -416.899344 -90)
		(property "Reference" "C6511"
			(at 0 0 270)
			(layer "F.SilkS")
			(hide yes)
			(effects
				(font
					(size 1.27 1.27)
				)
			)
		)
		(property "Value" ""
			(at 0 0 270)
			(layer "F.Fab")
			(effects
				(font
					(size 1.27 1.27)
				)
			)
		)
		(duplicate_pad_numbers_are_jumpers no)
		(fp_line
			(start -0.299974 0.150114)
			(end -0.299974 -0.150114)
			(stroke
				(width 0.1)
				(type default)
			)
			(layer "F.Fab")
		)
		(fp_line
			(start 0.299974 0.150114)
			(end -0.299974 0.150114)
			(stroke
				(width 0.1)
				(type default)
			)
			(layer "F.Fab")
		)
		(fp_line
			(start -0.299974 -0.150114)
			(end 0.299974 -0.150114)
			(stroke
				(width 0.1)
				(type default)
			)
			(layer "F.Fab")
		)
		(fp_line
			(start 0.299974 -0.150114)
			(end 0.299974 0.150114)
			(stroke
				(width 0.1)
				(type default)
			)
			(layer "F.Fab")
		)
		(pad "1" smd rect
			(at -0.2667 0 270)
			(size 0.3048 0.381)
			(layers "F.Cu" "F.Mask" "F.Paste")
			(net "P5E_CPU0_P0_TX_BUF_C_DP<5>")
		)
		(pad "2" smd rect
			(at 0.2667 0 270)
			(size 0.3048 0.381)
			(layers "F.Cu" "F.Mask" "F.Paste")
			(net "P5E_CPU0_P0_TX_BUF_DP<5>")
		)
	)
	(footprint ""
		(layer "F.Cu")
		(at 164.973 -96.012 90)
		(property "Reference" "C1058"
			(at 0 0 90)
			(layer "F.SilkS")
			(hide yes)
			(effects
				(font
					(size 1.27 1.27)
				)
			)
		)
		(property "Value" ""
			(at 0 0 90)
			(layer "F.Fab")
			(effects
				(font
					(size 1.27 1.27)
				)
			)
		)
		(duplicate_pad_numbers_are_jumpers no)
		(fp_line
			(start 0.7874 -0.4064)
			(end 0.7874 0.4064)
			(stroke
				(width 0.1524)
				(type default)
			)
			(layer "F.SilkS")
		)
		(fp_line
			(start -0.7874 -0.4064)
			(end 0.7874 -0.4064)
			(stroke
				(width 0.1524)
				(type default)
			)
			(layer "F.SilkS")
		)
		(fp_line
			(start 0.7874 0.4064)
			(end -0.7874 0.4064)
			(stroke
				(width 0.1524)
				(type default)
			)
			(layer "F.SilkS")
		)
		(fp_line
			(start -0.7874 0.4064)
			(end -0.7874 -0.4064)
			(stroke
				(width 0.1524)
				(type default)
			)
			(layer "F.SilkS")
		)
		(fp_line
			(start -0.12065 -0.305054)
			(end -0.12065 -0.2794)
			(stroke
				(width 0.1)
				(type default)
			)
			(layer "F.Fab")
		)
		(fp_line
			(start -0.67945 -0.305054)
			(end -0.12065 -0.305054)
			(stroke
				(width 0.1)
				(type default)
			)
			(layer "F.Fab")
		)
		(fp_line
			(start 0.67945 -0.3048)
			(end 0.67945 0.3048)
			(stroke
				(width 0.1)
				(type default)
			)
			(layer "F.Fab")
		)
		(fp_line
			(start 0.12065 -0.3048)
			(end 0.67945 -0.3048)
			(stroke
				(width 0.1)
				(type default)
			)
			(layer "F.Fab")
		)
		(fp_line
			(start 0.12065 -0.2794)
			(end 0.12065 -0.3048)
			(stroke
				(width 0.1)
				(type default)
			)
			(layer "F.Fab")
		)
		(fp_line
			(start -0.12065 -0.2794)
			(end 0.12065 -0.2794)
			(stroke
				(width 0.1)
				(type default)
			)
			(layer "F.Fab")
		)
		(fp_line
			(start 0.120396 0.2794)
			(end -0.12065 0.2794)
			(stroke
				(width 0.1)
				(type default)
			)
			(layer "F.Fab")
		)
		(fp_line
			(start -0.12065 0.2794)
			(end -0.12065 0.3048)
			(stroke
				(width 0.1)
				(type default)
			)
			(layer "F.Fab")
		)
		(fp_line
			(start 0.67945 0.3048)
			(end 0.120396 0.3048)
			(stroke
				(width 0.1)
				(type default)
			)
			(layer "F.Fab")
		)
		(fp_line
			(start 0.120396 0.3048)
			(end 0.120396 0.2794)
			(stroke
				(width 0.1)
				(type default)
			)
			(layer "F.Fab")
		)
		(fp_line
			(start -0.12065 0.3048)
			(end -0.67945 0.3048)
			(stroke
				(width 0.1)
				(type default)
			)
			(layer "F.Fab")
		)
		(fp_line
			(start -0.67945 0.3048)
			(end -0.67945 -0.305054)
			(stroke
				(width 0.1)
				(type default)
			)
			(layer "F.Fab")
		)
		(pad "1" smd circle
			(at -0.40005 0 90)
			(size 0 0)
			(layers "F.Cu" "F.Mask" "F.Paste")
			(net "P3V3_AUX")
		)
		(pad "2" smd circle
			(at 0.40005 0 90)
			(size 0 0)
			(layers "F.Cu" "F.Mask" "F.Paste")
			(net "GND")
		)
	)
)
